FILE_TYPE=LIBRARY_PARTS;
primitive 'CONN14_H54902001','CONN14_H54902001_THMT','CONN14_H54902001_PIP';
  pin
    'IO1':
      PIN_NUMBER='(1)';
      BIDIRECTIONAL='TRUE';
      INPUT_LOAD='(-0.01,0.01)';
      OUTPUT_LOAD='(1.0,-1.0)';
    'IO10':
      PIN_NUMBER='(10)';
      BIDIRECTIONAL='TRUE';
      INPUT_LOAD='(-0.01,0.01)';
      OUTPUT_LOAD='(1.0,-1.0)';
    'IO11':
      PIN_NUMBER='(11)';
      BIDIRECTIONAL='TRUE';
      INPUT_LOAD='(-0.01,0.01)';
      OUTPUT_LOAD='(1.0,-1.0)';
    'IO12':
      PIN_NUMBER='(12)';
      BIDIRECTIONAL='TRUE';
      INPUT_LOAD='(-0.01,0.01)';
      OUTPUT_LOAD='(1.0,-1.0)';
    'IO13':
      PIN_NUMBER='(13)';
      BIDIRECTIONAL='TRUE';
      INPUT_LOAD='(-0.01,0.01)';
      OUTPUT_LOAD='(1.0,-1.0)';
    'IO14':
      PIN_NUMBER='(14)';
      BIDIRECTIONAL='TRUE';
      INPUT_LOAD='(-0.01,0.01)';
      OUTPUT_LOAD='(1.0,-1.0)';
    'IO2':
      PIN_NUMBER='(2)';
      BIDIRECTIONAL='TRUE';
      INPUT_LOAD='(-0.01,0.01)';
      OUTPUT_LOAD='(1.0,-1.0)';
    'IO3':
      PIN_NUMBER='(3)';
      BIDIRECTIONAL='TRUE';
      INPUT_LOAD='(-0.01,0.01)';
      OUTPUT_LOAD='(1.0,-1.0)';
    'IO4':
      PIN_NUMBER='(4)';
      BIDIRECTIONAL='TRUE';
      INPUT_LOAD='(-0.01,0.01)';
      OUTPUT_LOAD='(1.0,-1.0)';
    'IO5':
      PIN_NUMBER='(5)';
      BIDIRECTIONAL='TRUE';
      INPUT_LOAD='(-0.01,0.01)';
      OUTPUT_LOAD='(1.0,-1.0)';
    'IO6':
      PIN_NUMBER='(6)';
      BIDIRECTIONAL='TRUE';
      INPUT_LOAD='(-0.01,0.01)';
      OUTPUT_LOAD='(1.0,-1.0)';
    'IO7':
      PIN_NUMBER='(7)';
      BIDIRECTIONAL='TRUE';
      INPUT_LOAD='(-0.01,0.01)';
      OUTPUT_LOAD='(1.0,-1.0)';
    'IO8':
      PIN_NUMBER='(8)';
      BIDIRECTIONAL='TRUE';
      INPUT_LOAD='(-0.01,0.01)';
      OUTPUT_LOAD='(1.0,-1.0)';
    'IO9':
      PIN_NUMBER='(9)';
      BIDIRECTIONAL='TRUE';
      INPUT_LOAD='(-0.01,0.01)';
      OUTPUT_LOAD='(1.0,-1.0)';
  end_pin;
  body
    PART_NAME='CONN14_H54902001';
    PHYS_DES_PREFIX='J';
  end_body;
end_primitive;

END.
